(kicad_pcb
	(version 20260206)
	(generator "pcbnew")
	(generator_version "10.0")
	(general
		(thickness 1.6)
		(legacy_teardrops no)
	)
	(paper "A4")
	(title_block
		(title "baseboard — 13948-1b.1110WZS1818.brd")
		(comment 1 "Honey Badger (Wiwynn) / footprints 218-225 of 2523")
	)
	(layers
		(0 "F.Cu" signal "TOP")
		(4 "In1.Cu" signal "L2GND")
		(6 "In2.Cu" signal "L3")
		(8 "In3.Cu" signal "L4VCC")
		(10 "In4.Cu" signal "L5VCC")
		(12 "In5.Cu" signal "L6")
		(14 "In6.Cu" signal "L7GND")
		(2 "B.Cu" signal "BOTTOM")
		(9 "F.Adhes" user "F.Adhesive")
		(11 "B.Adhes" user "B.Adhesive")
		(13 "F.Paste" user "Package Geometry/Pastemask Top")
		(15 "B.Paste" user "Package Geometry/Pastemask Bottom")
		(5 "F.SilkS" user "Ref Des/Silkscreen Top")
		(7 "B.SilkS" user "Ref Des/Silkscreen Bottom")
		(1 "F.Mask" user "Board Geometry/Soldermask Top")
		(3 "B.Mask" user "Board Geometry/Soldermask Bottom")
		(17 "Dwgs.User" user "User.Drawings")
		(19 "Cmts.User" user "User.Comments")
		(21 "Eco1.User" user "User.Eco1")
		(23 "Eco2.User" user "User.Eco2")
		(25 "Edge.Cuts" user "Board Geometry/Outline")
		(27 "Margin" user)
		(31 "F.CrtYd" user "Package Geometry/Place Bound Top")
		(29 "B.CrtYd" user "Package Geometry/Place Bound Bottom")
		(35 "F.Fab" user "Ref Des/Assembly Top")
		(33 "B.Fab" user "Ref Des/Assembly Bottom")
	)
	(footprint ""
		(layer "F.Cu")
		(at 279.781 -182.372)
		(property "Reference" "TP98"
			(at 0 0 0)
			(layer "F.SilkS")
			(hide yes)
			(effects
				(font
					(size 1.27 1.27)
				)
			)
		)
		(property "Value" "TPAD28"
			(at 0.0127 -1.8034 0)
			(unlocked yes)
			(layer "F.Fab")
			(hide yes)
			(effects
				(font
					(size 1.016 1.016)
					(thickness 0.1524)
				)
			)
		)
		(property "Device Type" "TPAD28"
			(at 0.0127 -3.3274 0)
			(unlocked yes)
			(layer "F.Fab")
			(hide yes)
			(effects
				(font
					(size 1.016 1.016)
					(thickness 0.1524)
				)
			)
		)
		(duplicate_pad_numbers_are_jumpers no)
		(fp_poly
			(pts
				(arc
					(start 0.3556 0)
					(mid -0.3556 0)
					(end 0.3556 0)
				)
			)
			(stroke
				(width 0)
				(type default)
			)
			(fill no)
			(layer "F.CrtYd")
		)
		(fp_poly
			(pts
				(arc
					(start 0.6096 0)
					(mid -0.6096 0)
					(end 0.6096 0)
				)
			)
			(stroke
				(width 0)
				(type default)
			)
			(fill no)
			(layer "F.Fab")
		)
		(pad "1" smd circle
			(at 0 0)
			(size 0.7112 0.7112)
			(layers "F.Cu" "F.Mask" "F.Paste")
			(net "TP_BMC_GPIOR5")
		)
	)
	(footprint ""
		(layer "F.Cu")
		(at 285.75 -161.544 180)
		(property "Reference" "R328"
			(at 0 0 180)
			(layer "F.SilkS")
			(hide yes)
			(effects
				(font
					(size 1.27 1.27)
				)
			)
		)
		(property "Value" "0R2J-2-GP"
			(at 0.064008 -3.993896 180)
			(unlocked yes)
			(layer "F.Fab")
			(hide yes)
			(effects
				(font
					(size 1.016 1.016)
					(thickness 0.1524)
				)
			)
		)
		(property "Device Type" "R402H16"
			(at 0.064008 -5.517896 180)
			(unlocked yes)
			(layer "F.Fab")
			(hide yes)
			(effects
				(font
					(size 1.016 1.016)
					(thickness 0.1524)
				)
			)
		)
		(duplicate_pad_numbers_are_jumpers no)
		(fp_line
			(start 0.508 -0.9398)
			(end -0.508 -0.9398)
			(stroke
				(width 0.1524)
				(type default)
			)
			(layer "F.SilkS")
		)
		(fp_line
			(start -0.508 -0.9398)
			(end -0.508 0.9398)
			(stroke
				(width 0.1524)
				(type default)
			)
			(layer "F.SilkS")
		)
		(fp_rect
			(start -0.508 0.9398)
			(end 0.508 -0.9398)
			(stroke
				(width 0)
				(type default)
			)
			(fill no)
			(layer "F.CrtYd")
		)
		(fp_rect
			(start -0.508 0.9398)
			(end 0.508 -0.9398)
			(stroke
				(width 0)
				(type default)
			)
			(fill no)
			(layer "F.Fab")
		)
		(pad "1" smd custom
			(at 0 -0.4445 180)
			(size 0.1397 0.1397)
			(layers "F.Cu" "F.Mask" "F.Paste")
			(net "SYS_RSTBTN_N")
			(options
				(clearance outline)
				(anchor circle)
			)
			(primitives
				(gr_poly
					(pts
						(arc
							(start -0.1778 -0.2794)
							(mid -0.249642 -0.249642)
							(end -0.2794 -0.1778)
						)
						(arc
							(start -0.2794 0.1778)
							(mid -0.249642 0.249642)
							(end -0.1778 0.2794)
						)
						(arc
							(start 0.1778 0.2794)
							(mid 0.249642 0.249642)
							(end 0.2794 0.1778)
						)
						(arc
							(start 0.2794 -0.1778)
							(mid 0.249642 -0.249642)
							(end 0.1778 -0.2794)
						)
					)
					(width 0)
					(fill yes)
				)
			)
		)
		(pad "2" smd custom
			(at 0 0.4445 180)
			(size 0.1397 0.1397)
			(layers "F.Cu" "F.Mask" "F.Paste")
			(net "SYS_RSTBTN_N_R")
			(options
				(clearance outline)
				(anchor circle)
			)
			(primitives
				(gr_poly
					(pts
						(arc
							(start -0.1778 -0.2794)
							(mid -0.249642 -0.249642)
							(end -0.2794 -0.1778)
						)
						(arc
							(start -0.2794 0.1778)
							(mid -0.249642 0.249642)
							(end -0.1778 0.2794)
						)
						(arc
							(start 0.1778 0.2794)
							(mid 0.249642 0.249642)
							(end 0.2794 0.1778)
						)
						(arc
							(start 0.2794 -0.1778)
							(mid 0.249642 -0.249642)
							(end 0.1778 -0.2794)
						)
					)
					(width 0)
					(fill yes)
				)
			)
		)
	)
	(footprint ""
		(layer "F.Cu")
		(at 103.01097 -76.454)
		(property "Reference" "SR859"
			(at 0 0 0)
			(layer "F.SilkS")
			(hide yes)
			(effects
				(font
					(size 1.27 1.27)
				)
			)
		)
		(property "Value" "0R2J-2-GP"
			(at 0.064008 -3.993896 0)
			(unlocked yes)
			(layer "F.Fab")
			(hide yes)
			(effects
				(font
					(size 1.016 1.016)
					(thickness 0.1524)
				)
			)
		)
		(property "Device Type" "R402H16"
			(at 0.064008 -5.517896 0)
			(unlocked yes)
			(layer "F.Fab")
			(hide yes)
			(effects
				(font
					(size 1.016 1.016)
					(thickness 0.1524)
				)
			)
		)
		(duplicate_pad_numbers_are_jumpers no)
		(fp_line
			(start -0.508 -0.9398)
			(end -0.508 0.9398)
			(stroke
				(width 0.1524)
				(type default)
			)
			(layer "F.SilkS")
		)
		(fp_line
			(start 0.508 -0.9398)
			(end -0.508 -0.9398)
			(stroke
				(width 0.1524)
				(type default)
			)
			(layer "F.SilkS")
		)
		(fp_rect
			(start -0.508 0.9398)
			(end 0.508 -0.9398)
			(stroke
				(width 0)
				(type default)
			)
			(fill no)
			(layer "F.CrtYd")
		)
		(fp_rect
			(start -0.508 0.9398)
			(end 0.508 -0.9398)
			(stroke
				(width 0)
				(type default)
			)
			(fill no)
			(layer "F.Fab")
		)
		(pad "1" smd custom
			(at 0 -0.4445)
			(size 0.1397 0.1397)
			(layers "F.Cu" "F.Mask" "F.Paste")
			(net "JTAG_EXP_TDI")
			(options
				(clearance outline)
				(anchor circle)
			)
			(primitives
				(gr_poly
					(pts
						(arc
							(start -0.1778 -0.2794)
							(mid -0.249642 -0.249642)
							(end -0.2794 -0.1778)
						)
						(arc
							(start -0.2794 0.1778)
							(mid -0.249642 0.249642)
							(end -0.1778 0.2794)
						)
						(arc
							(start 0.1778 0.2794)
							(mid 0.249642 0.249642)
							(end 0.2794 0.1778)
						)
						(arc
							(start 0.2794 -0.1778)
							(mid 0.249642 -0.249642)
							(end 0.1778 -0.2794)
						)
					)
					(width 0)
					(fill yes)
				)
			)
		)
		(pad "2" smd custom
			(at 0 0.4445)
			(size 0.1397 0.1397)
			(layers "F.Cu" "F.Mask" "F.Paste")
			(net "JTAG_BMC_L_TDO")
			(options
				(clearance outline)
				(anchor circle)
			)
			(primitives
				(gr_poly
					(pts
						(arc
							(start -0.1778 -0.2794)
							(mid -0.249642 -0.249642)
							(end -0.2794 -0.1778)
						)
						(arc
							(start -0.2794 0.1778)
							(mid -0.249642 0.249642)
							(end -0.1778 0.2794)
						)
						(arc
							(start 0.1778 0.2794)
							(mid 0.249642 0.249642)
							(end 0.2794 0.1778)
						)
						(arc
							(start 0.2794 -0.1778)
							(mid 0.249642 -0.249642)
							(end 0.1778 -0.2794)
						)
					)
					(width 0)
					(fill yes)
				)
			)
		)
	)
	(footprint ""
		(layer "F.Cu")
		(at 291.592 -150.495 90)
		(property "Reference" "C233"
			(at 0 0 90)
			(layer "F.SilkS")
			(hide yes)
			(effects
				(font
					(size 1.27 1.27)
				)
			)
		)
		(property "Value" "SC1U6D3V3KX-2GP"
			(at 0 -2.8194 90)
			(unlocked yes)
			(layer "F.Fab")
			(hide yes)
			(effects
				(font
					(size 1.016 1.016)
					(thickness 0.1524)
				)
			)
		)
		(property "Device Type" "C603H36"
			(at 0 -4.3434 90)
			(unlocked yes)
			(layer "F.Fab")
			(hide yes)
			(effects
				(font
					(size 1.016 1.016)
					(thickness 0.1524)
				)
			)
		)
		(duplicate_pad_numbers_are_jumpers no)
		(fp_line
			(start 0.508 0)
			(end -0.508 0)
			(stroke
				(width 0.2032)
				(type default)
			)
			(layer "F.SilkS")
		)
		(fp_rect
			(start -0.5842 1.3335)
			(end 0.5842 -1.3335)
			(stroke
				(width 0)
				(type default)
			)
			(fill no)
			(layer "F.CrtYd")
		)
		(fp_rect
			(start -0.5842 1.3335)
			(end 0.5842 -1.3335)
			(stroke
				(width 0)
				(type default)
			)
			(fill no)
			(layer "F.Fab")
		)
		(pad "1" smd custom
			(at 0 -0.762 90)
			(size 0.2159 0.2159)
			(layers "F.Cu" "F.Mask" "F.Paste")
			(net "P3V3_STBY")
			(options
				(clearance outline)
				(anchor circle)
			)
			(primitives
				(gr_poly
					(pts
						(arc
							(start -0.3302 -0.4318)
							(mid -0.402042 -0.402042)
							(end -0.4318 -0.3302)
						)
						(arc
							(start -0.4318 0.3302)
							(mid -0.402042 0.402042)
							(end -0.3302 0.4318)
						)
						(arc
							(start 0.3302 0.4318)
							(mid 0.402042 0.402042)
							(end 0.4318 0.3302)
						)
						(arc
							(start 0.4318 -0.3302)
							(mid 0.402042 -0.402042)
							(end 0.3302 -0.4318)
						)
					)
					(width 0)
					(fill yes)
				)
			)
		)
		(pad "2" smd custom
			(at 0 0.762 90)
			(size 0.2159 0.2159)
			(layers "F.Cu" "F.Mask" "F.Paste")
			(net "GND")
			(options
				(clearance outline)
				(anchor circle)
			)
			(primitives
				(gr_poly
					(pts
						(arc
							(start -0.3302 -0.4318)
							(mid -0.402042 -0.402042)
							(end -0.4318 -0.3302)
						)
						(arc
							(start -0.4318 0.3302)
							(mid -0.402042 0.402042)
							(end -0.3302 0.4318)
						)
						(arc
							(start 0.3302 0.4318)
							(mid 0.402042 0.402042)
							(end 0.4318 0.3302)
						)
						(arc
							(start 0.4318 -0.3302)
							(mid 0.402042 -0.402042)
							(end 0.3302 -0.4318)
						)
					)
					(width 0)
					(fill yes)
				)
			)
		)
	)
	(footprint ""
		(layer "F.Cu")
		(at 194.183 -35.179 -90)
		(property "Reference" "R464"
			(at 0 0 270)
			(layer "F.SilkS")
			(hide yes)
			(effects
				(font
					(size 1.27 1.27)
				)
			)
		)
		(property "Value" "0R2J-2-GP"
			(at 0.064008 -3.993896 270)
			(unlocked yes)
			(layer "F.Fab")
			(hide yes)
			(effects
				(font
					(size 1.016 1.016)
					(thickness 0.1524)
				)
			)
		)
		(property "Device Type" "R402H16"
			(at 0.064008 -5.517896 270)
			(unlocked yes)
			(layer "F.Fab")
			(hide yes)
			(effects
				(font
					(size 1.016 1.016)
					(thickness 0.1524)
				)
			)
		)
		(duplicate_pad_numbers_are_jumpers no)
		(fp_line
			(start -0.508 -0.9398)
			(end -0.508 0.9398)
			(stroke
				(width 0.1524)
				(type default)
			)
			(layer "F.SilkS")
		)
		(fp_line
			(start 0.508 -0.9398)
			(end -0.508 -0.9398)
			(stroke
				(width 0.1524)
				(type default)
			)
			(layer "F.SilkS")
		)
		(fp_rect
			(start -0.508 0.9398)
			(end 0.508 -0.9398)
			(stroke
				(width 0)
				(type default)
			)
			(fill no)
			(layer "F.CrtYd")
		)
		(fp_rect
			(start -0.508 0.9398)
			(end 0.508 -0.9398)
			(stroke
				(width 0)
				(type default)
			)
			(fill no)
			(layer "F.Fab")
		)
		(pad "1" smd custom
			(at 0 -0.4445 270)
			(size 0.1397 0.1397)
			(layers "F.Cu" "F.Mask" "F.Paste")
			(net "GND")
			(options
				(clearance outline)
				(anchor circle)
			)
			(primitives
				(gr_poly
					(pts
						(arc
							(start -0.1778 -0.2794)
							(mid -0.249642 -0.249642)
							(end -0.2794 -0.1778)
						)
						(arc
							(start -0.2794 0.1778)
							(mid -0.249642 0.249642)
							(end -0.1778 0.2794)
						)
						(arc
							(start 0.1778 0.2794)
							(mid 0.249642 0.249642)
							(end 0.2794 0.1778)
						)
						(arc
							(start 0.2794 -0.1778)
							(mid 0.249642 -0.249642)
							(end 0.1778 -0.2794)
						)
					)
					(width 0)
					(fill yes)
				)
			)
		)
		(pad "2" smd custom
			(at 0 0.4445 270)
			(size 0.1397 0.1397)
			(layers "F.Cu" "F.Mask" "F.Paste")
			(net "RMII_BMC_PHY_TXD0")
			(options
				(clearance outline)
				(anchor circle)
			)
			(primitives
				(gr_poly
					(pts
						(arc
							(start -0.1778 -0.2794)
							(mid -0.249642 -0.249642)
							(end -0.2794 -0.1778)
						)
						(arc
							(start -0.2794 0.1778)
							(mid -0.249642 0.249642)
							(end -0.1778 0.2794)
						)
						(arc
							(start 0.1778 0.2794)
							(mid 0.249642 0.249642)
							(end 0.2794 0.1778)
						)
						(arc
							(start 0.2794 -0.1778)
							(mid 0.249642 -0.249642)
							(end 0.1778 -0.2794)
						)
					)
					(width 0)
					(fill yes)
				)
			)
		)
	)
	(footprint ""
		(layer "F.Cu")
		(at 88.011 -231.775 180)
		(property "Reference" "R669"
			(at 0 0 180)
			(layer "F.SilkS")
			(hide yes)
			(effects
				(font
					(size 1.27 1.27)
				)
			)
		)
		(property "Value" "0R2J-2-GP"
			(at 0.064008 -3.993896 180)
			(unlocked yes)
			(layer "F.Fab")
			(hide yes)
			(effects
				(font
					(size 1.016 1.016)
					(thickness 0.1524)
				)
			)
		)
		(property "Device Type" "R402H16"
			(at 0.064008 -5.517896 180)
			(unlocked yes)
			(layer "F.Fab")
			(hide yes)
			(effects
				(font
					(size 1.016 1.016)
					(thickness 0.1524)
				)
			)
		)
		(duplicate_pad_numbers_are_jumpers no)
		(fp_line
			(start 0.508 -0.9398)
			(end -0.508 -0.9398)
			(stroke
				(width 0.1524)
				(type default)
			)
			(layer "F.SilkS")
		)
		(fp_line
			(start -0.508 -0.9398)
			(end -0.508 0.9398)
			(stroke
				(width 0.1524)
				(type default)
			)
			(layer "F.SilkS")
		)
		(fp_rect
			(start -0.508 0.9398)
			(end 0.508 -0.9398)
			(stroke
				(width 0)
				(type default)
			)
			(fill no)
			(layer "F.CrtYd")
		)
		(fp_rect
			(start -0.508 0.9398)
			(end 0.508 -0.9398)
			(stroke
				(width 0)
				(type default)
			)
			(fill no)
			(layer "F.Fab")
		)
		(pad "1" smd custom
			(at 0 -0.4445 180)
			(size 0.1397 0.1397)
			(layers "F.Cu" "F.Mask" "F.Paste")
			(net "SAS_FAULT_LED12")
			(options
				(clearance outline)
				(anchor circle)
			)
			(primitives
				(gr_poly
					(pts
						(arc
							(start -0.1778 -0.2794)
							(mid -0.249642 -0.249642)
							(end -0.2794 -0.1778)
						)
						(arc
							(start -0.2794 0.1778)
							(mid -0.249642 0.249642)
							(end -0.1778 0.2794)
						)
						(arc
							(start 0.1778 0.2794)
							(mid 0.249642 0.249642)
							(end 0.2794 0.1778)
						)
						(arc
							(start 0.2794 -0.1778)
							(mid 0.249642 -0.249642)
							(end 0.1778 -0.2794)
						)
					)
					(width 0)
					(fill yes)
				)
			)
		)
		(pad "2" smd custom
			(at 0 0.4445 180)
			(size 0.1397 0.1397)
			(layers "F.Cu" "F.Mask" "F.Paste")
			(net "SAS_HDD_LED_12")
			(options
				(clearance outline)
				(anchor circle)
			)
			(primitives
				(gr_poly
					(pts
						(arc
							(start -0.1778 -0.2794)
							(mid -0.249642 -0.249642)
							(end -0.2794 -0.1778)
						)
						(arc
							(start -0.2794 0.1778)
							(mid -0.249642 0.249642)
							(end -0.1778 0.2794)
						)
						(arc
							(start 0.1778 0.2794)
							(mid 0.249642 0.249642)
							(end 0.2794 0.1778)
						)
						(arc
							(start 0.2794 -0.1778)
							(mid 0.249642 -0.249642)
							(end 0.1778 -0.2794)
						)
					)
					(width 0)
					(fill yes)
				)
			)
		)
	)
	(footprint ""
		(layer "F.Cu")
		(at 105.29697 -114.3 180)
		(property "Reference" "SC1086"
			(at 0 0 180)
			(layer "F.SilkS")
			(hide yes)
			(effects
				(font
					(size 1.27 1.27)
				)
			)
		)
		(property "Value" "SCD01U10V1KX-GP"
			(at -2.8321 -1.7399 180)
			(unlocked yes)
			(layer "F.Fab")
			(hide yes)
			(effects
				(font
					(size 1.016 1.016)
					(thickness 0.1524)
				)
			)
		)
		(property "Device Type" "C0201H13"
			(at -2.8321 -3.2639 180)
			(unlocked yes)
			(layer "F.Fab")
			(hide yes)
			(effects
				(font
					(size 1.016 1.016)
					(thickness 0.1524)
				)
			)
		)
		(duplicate_pad_numbers_are_jumpers no)
		(fp_rect
			(start -0.2794 0.6477)
			(end 0.2794 -0.6477)
			(stroke
				(width 0)
				(type default)
			)
			(fill no)
			(layer "F.CrtYd")
		)
		(fp_rect
			(start -0.2794 0.6477)
			(end 0.2794 -0.6477)
			(stroke
				(width 0)
				(type default)
			)
			(fill no)
			(layer "F.Fab")
		)
		(pad "1" smd custom
			(at 0 -0.2794 180)
			(size 0.0762 0.0762)
			(layers "F.Cu" "F.Mask" "F.Paste")
			(net "SAS_HDD_TX9_N")
			(options
				(clearance outline)
				(anchor circle)
			)
			(primitives
				(gr_poly
					(pts
						(arc
							(start 0.1524 -0.127)
							(mid 0.137521 -0.162921)
							(end 0.1016 -0.1778)
						)
						(arc
							(start -0.1016 -0.1778)
							(mid -0.137521 -0.162921)
							(end -0.1524 -0.127)
						)
						(arc
							(start -0.1524 0.127)
							(mid -0.137521 0.162921)
							(end -0.1016 0.1778)
						)
						(arc
							(start 0.1016 0.1778)
							(mid 0.137521 0.162921)
							(end 0.1524 0.127)
						)
					)
					(width 0)
					(fill yes)
				)
			)
		)
		(pad "2" smd custom
			(at 0 0.2794 180)
			(size 0.0762 0.0762)
			(layers "F.Cu" "F.Mask" "F.Paste")
			(net "SAS_EXP_GF_TX_DN13")
			(options
				(clearance outline)
				(anchor circle)
			)
			(primitives
				(gr_poly
					(pts
						(arc
							(start 0.1524 -0.127)
							(mid 0.137521 -0.162921)
							(end 0.1016 -0.1778)
						)
						(arc
							(start -0.1016 -0.1778)
							(mid -0.137521 -0.162921)
							(end -0.1524 -0.127)
						)
						(arc
							(start -0.1524 0.127)
							(mid -0.137521 0.162921)
							(end -0.1016 0.1778)
						)
						(arc
							(start 0.1016 0.1778)
							(mid 0.137521 0.162921)
							(end 0.1524 0.127)
						)
					)
					(width 0)
					(fill yes)
				)
			)
		)
	)
	(footprint ""
		(layer "F.Cu")
		(at 271.272 -169.672 90)
		(property "Reference" "R268"
			(at 0 0 90)
			(layer "F.SilkS")
			(hide yes)
			(effects
				(font
					(size 1.27 1.27)
				)
			)
		)
		(property "Value" "10KR2F-2-GP"
			(at 0.064008 -3.993896 90)
			(unlocked yes)
			(layer "F.Fab")
			(hide yes)
			(effects
				(font
					(size 1.016 1.016)
					(thickness 0.1524)
				)
			)
		)
		(property "Device Type" "R402H16"
			(at 0.064008 -5.517896 90)
			(unlocked yes)
			(layer "F.Fab")
			(hide yes)
			(effects
				(font
					(size 1.016 1.016)
					(thickness 0.1524)
				)
			)
		)
		(duplicate_pad_numbers_are_jumpers no)
		(fp_line
			(start 0.508 -0.9398)
			(end -0.508 -0.9398)
			(stroke
				(width 0.1524)
				(type default)
			)
			(layer "F.SilkS")
		)
		(fp_line
			(start -0.508 -0.9398)
			(end -0.508 0.9398)
			(stroke
				(width 0.1524)
				(type default)
			)
			(layer "F.SilkS")
		)
		(fp_rect
			(start -0.508 0.9398)
			(end 0.508 -0.9398)
			(stroke
				(width 0)
				(type default)
			)
			(fill no)
			(layer "F.CrtYd")
		)
		(fp_rect
			(start -0.508 0.9398)
			(end 0.508 -0.9398)
			(stroke
				(width 0)
				(type default)
			)
			(fill no)
			(layer "F.Fab")
		)
		(pad "1" smd custom
			(at 0 -0.4445 90)
			(size 0.1397 0.1397)
			(layers "F.Cu" "F.Mask" "F.Paste")
			(net "P3V3_STBY")
			(options
				(clearance outline)
				(anchor circle)
			)
			(primitives
				(gr_poly
					(pts
						(arc
							(start -0.1778 -0.2794)
							(mid -0.249642 -0.249642)
							(end -0.2794 -0.1778)
						)
						(arc
							(start -0.2794 0.1778)
							(mid -0.249642 0.249642)
							(end -0.1778 0.2794)
						)
						(arc
							(start 0.1778 0.2794)
							(mid 0.249642 0.249642)
							(end 0.2794 0.1778)
						)
						(arc
							(start 0.2794 -0.1778)
							(mid 0.249642 -0.249642)
							(end 0.1778 -0.2794)
						)
					)
					(width 0)
					(fill yes)
				)
			)
		)
		(pad "2" smd custom
			(at 0 0.4445 90)
			(size 0.1397 0.1397)
			(layers "F.Cu" "F.Mask" "F.Paste")
			(net "BMC_MBC_I2C_E_SDA")
			(options
				(clearance outline)
				(anchor circle)
			)
			(primitives
				(gr_poly
					(pts
						(arc
							(start -0.1778 -0.2794)
							(mid -0.249642 -0.249642)
							(end -0.2794 -0.1778)
						)
						(arc
							(start -0.2794 0.1778)
							(mid -0.249642 0.249642)
							(end -0.1778 0.2794)
						)
						(arc
							(start 0.1778 0.2794)
							(mid 0.249642 0.249642)
							(end 0.2794 0.1778)
						)
						(arc
							(start 0.2794 -0.1778)
							(mid 0.249642 -0.249642)
							(end 0.1778 -0.2794)
						)
					)
					(width 0)
					(fill yes)
				)
			)
		)
	)
)
